# BASEBOARD_FAB2 (Tioga Pass) — schematic netlist excerpt (pin names and nets, part order shuffled) for the footprints in the layout excerpt that follows; sources: Cadence DE-HDL packaged netlist, KiCad conversion of Wiwynn_Tioga_Pass_MB.brd

R25W106  RES  4.75K 1% EMPTY  pkg 0402  page 150 : A = P3V3_STBY ; B = RMII_BMC_OCP_TXEN
C25W42  CAP  1.0UF 16V 10% X6S  pkg 0402  page 149 : A = VCC_D_3V3 ; B = GND
C4P10  CAP  47UF 4V 20% X6S  pkg 0805  page 42 : A = PVCCIO_CPU0 ; B = GND

(kicad_pcb
	(version 20260206)
	(generator "pcbnew")
	(generator_version "10.0")
	(general
		(thickness 1.6)
		(legacy_teardrops no)
	)
	(paper "A4")
	(title_block
		(title "Wiwynn_Tioga_Pass_MB.brd")
		(comment 1 "Tioga Pass / footprints 3296-3298 of 4770")
	)
	(layers
		(0 "F.Cu" signal "TOP")
		(4 "In1.Cu" signal "L2GND")
		(6 "In2.Cu" signal "L3")
		(8 "In3.Cu" signal "L4GND")
		(10 "In4.Cu" signal "L5")
		(12 "In5.Cu" signal "L6GND")
		(14 "In6.Cu" signal "L7VCC")
		(16 "In7.Cu" signal "L8VCC")
		(18 "In8.Cu" signal "L9GND")
		(20 "In9.Cu" signal "L10")
		(22 "In10.Cu" signal "L11GND")
		(24 "In11.Cu" signal "L12")
		(26 "In12.Cu" signal "L13GND")
		(2 "B.Cu" signal "BOTTOM")
		(9 "F.Adhes" user "F.Adhesive")
		(11 "B.Adhes" user "B.Adhesive")
		(13 "F.Paste" user "Package Geometry/Pastemask Top")
		(15 "B.Paste" user "Package Geometry/Pastemask Bottom")
		(5 "F.SilkS" user "Ref Des/Silkscreen Top")
		(7 "B.SilkS" user "Ref Des/Silkscreen Bottom")
		(1 "F.Mask" user "Board Geometry/Soldermask Top")
		(3 "B.Mask" user "Board Geometry/Soldermask Bottom")
		(17 "Dwgs.User" user "User.Drawings")
		(19 "Cmts.User" user "User.Comments")
		(21 "Eco1.User" user "User.Eco1")
		(23 "Eco2.User" user "User.Eco2")
		(25 "Edge.Cuts" user "Board Geometry/Outline")
		(27 "Margin" user)
		(31 "F.CrtYd" user "Package Geometry/Place Bound Top")
		(29 "B.CrtYd" user "Package Geometry/Place Bound Bottom")
		(35 "F.Fab" user "Ref Des/Assembly Top")
		(33 "B.Fab" user "Ref Des/Assembly Bottom")
	)
	(footprint ""
		(layer "B.Cu")
		(at 401.701 -34.798 90)
		(property "Reference" "R25W106"
			(at 0.8382 -0.67818 90)
			(unlocked yes)
			(layer "B.SilkS")
			(effects
				(font
					(size 0.4064 0.254)
					(thickness 0.1524)
				)
				(justify left mirror)
			)
		)
		(property "Value" ""
			(at 0 0 90)
			(layer "B.Fab")
			(effects
				(font
					(size 1.27 1.27)
				)
				(justify mirror)
			)
		)
		(duplicate_pad_numbers_are_jumpers no)
		(fp_poly
			(pts
				(xy 0.2794 -0.1016) (xy -0.2794 -0.1016) (xy -0.2794 0.9906) (xy 0.2794 0.9906)
			)
			(stroke
				(width 0)
				(type default)
			)
			(fill no)
			(layer "B.CrtYd")
		)
		(fp_line
			(start 0.2794 -0.1016)
			(end 0.2794 0.9906)
			(stroke
				(width 0.1)
				(type default)
			)
			(layer "B.Fab")
		)
		(fp_line
			(start -0.2794 -0.1016)
			(end 0.2794 -0.1016)
			(stroke
				(width 0.1)
				(type default)
			)
			(layer "B.Fab")
		)
		(fp_line
			(start 0.2794 0.9906)
			(end -0.2794 0.9906)
			(stroke
				(width 0.1)
				(type default)
			)
			(layer "B.Fab")
		)
		(fp_line
			(start -0.2794 0.9906)
			(end -0.2794 -0.1016)
			(stroke
				(width 0.1)
				(type default)
			)
			(layer "B.Fab")
		)
		(pad "1" smd rect
			(at 0 0 270)
			(size 0.508 0.508)
			(layers "B.Cu" "B.Mask" "B.Paste")
			(net "P3V3_STBY")
		)
		(pad "2" smd rect
			(at 0 0.889 270)
			(size 0.508 0.508)
			(layers "B.Cu" "B.Mask" "B.Paste")
			(net "RMII_BMC_OCP_TXEN")
		)
		(zone
			(layer "B.Cu")
			(hatch none 0.5)
			(connect_pads
				(clearance 0)
			)
			(min_thickness 0.25)
			(keepout
				(tracks allowed)
				(vias not_allowed)
				(pads allowed)
				(copperpour not_allowed)
				(footprints allowed)
			)
			(placement
				(enabled no)
				(sheetname "")
			)
			(fill
				(thermal_gap 0.5)
				(thermal_bridge_width 0.5)
				(island_removal_mode 0)
			)
			(polygon
				(pts
					(xy 401.955 -35.052) (xy 401.955 -34.544) (xy 402.336 -34.544) (xy 402.336 -35.052)
				)
			)
		)
		(zone
			(layer "B.Cu")
			(hatch none 0.5)
			(connect_pads
				(clearance 0)
			)
			(min_thickness 0.25)
			(keepout
				(tracks not_allowed)
				(vias allowed)
				(pads allowed)
				(copperpour not_allowed)
				(footprints allowed)
			)
			(placement
				(enabled no)
				(sheetname "")
			)
			(fill
				(thermal_gap 0.5)
				(thermal_bridge_width 0.5)
				(island_removal_mode 0)
			)
			(polygon
				(pts
					(xy 402.336 -35.052) (xy 402.336 -34.544) (xy 401.955 -34.544) (xy 401.955 -35.052)
				)
			)
		)
	)
	(footprint ""
		(layer "B.Cu")
		(at 278.576024 -69.809614 -90)
		(property "Reference" "C4P10"
			(at 0 0 90)
			(layer "B.SilkS")
			(hide yes)
			(effects
				(font
					(size 1.27 1.27)
				)
				(justify mirror)
			)
		)
		(property "Value" ""
			(at 0 0 90)
			(layer "B.Fab")
			(effects
				(font
					(size 1.27 1.27)
				)
				(justify mirror)
			)
		)
		(duplicate_pad_numbers_are_jumpers no)
		(fp_poly
			(pts
				(xy 0.7239 -0.2159) (xy -0.7239 -0.2159) (xy -0.7239 1.9939) (xy 0.7239 1.9939)
			)
			(stroke
				(width 0)
				(type default)
			)
			(fill no)
			(layer "B.CrtYd")
		)
		(fp_line
			(start -0.7239 1.9939)
			(end -0.7239 -0.2159)
			(stroke
				(width 0.1)
				(type default)
			)
			(layer "B.Fab")
		)
		(fp_line
			(start 0.7239 1.9939)
			(end -0.7239 1.9939)
			(stroke
				(width 0.1)
				(type default)
			)
			(layer "B.Fab")
		)
		(fp_line
			(start -0.7239 -0.2159)
			(end 0.7239 -0.2159)
			(stroke
				(width 0.1)
				(type default)
			)
			(layer "B.Fab")
		)
		(fp_line
			(start 0.7239 -0.2159)
			(end 0.7239 1.9939)
			(stroke
				(width 0.1)
				(type default)
			)
			(layer "B.Fab")
		)
		(pad "1" smd rect
			(at 0 0 90)
			(size 1.27 1.016)
			(layers "B.Cu" "B.Mask" "B.Paste")
			(net "PVCCIO_CPU0")
		)
		(pad "2" smd rect
			(at 0 1.778 90)
			(size 1.27 1.016)
			(layers "B.Cu" "B.Mask" "B.Paste")
			(net "GND")
		)
		(zone
			(layer "B.Cu")
			(hatch none 0.5)
			(connect_pads
				(clearance 0)
			)
			(min_thickness 0.25)
			(keepout
				(tracks not_allowed)
				(vias allowed)
				(pads allowed)
				(copperpour not_allowed)
				(footprints allowed)
			)
			(placement
				(enabled no)
				(sheetname "")
			)
			(fill
				(thermal_gap 0.5)
				(thermal_bridge_width 0.5)
				(island_removal_mode 0)
			)
			(polygon
				(pts
					(xy 278.068024 -69.174614) (xy 278.068024 -70.444614) (xy 277.306024 -70.444614) (xy 277.306024 -69.174614)
				)
			)
		)
	)
	(footprint ""
		(layer "B.Cu")
		(at 411.503368 -39.63797 -90)
		(property "Reference" "C25W42"
			(at 0.8382 -0.67818 270)
			(unlocked yes)
			(layer "B.SilkS")
			(effects
				(font
					(size 0.4064 0.254)
					(thickness 0.1524)
				)
				(justify left mirror)
			)
		)
		(property "Value" ""
			(at 0 0 90)
			(layer "B.Fab")
			(effects
				(font
					(size 1.27 1.27)
				)
				(justify mirror)
			)
		)
		(duplicate_pad_numbers_are_jumpers no)
		(fp_poly
			(pts
				(xy -0.3048 -0.1016) (xy -0.3048 0.9906) (xy 0.3048 0.9906) (xy 0.3048 -0.1016)
			)
			(stroke
				(width 0)
				(type default)
			)
			(fill no)
			(layer "B.CrtYd")
		)
		(fp_line
			(start -0.3048 0.9906)
			(end -0.3048 -0.1016)
			(stroke
				(width 0.1)
				(type default)
			)
			(layer "B.Fab")
		)
		(fp_line
			(start 0.3048 0.9906)
			(end -0.3048 0.9906)
			(stroke
				(width 0.1)
				(type default)
			)
			(layer "B.Fab")
		)
		(fp_line
			(start -0.3048 -0.1016)
			(end 0.3048 -0.1016)
			(stroke
				(width 0.1)
				(type default)
			)
			(layer "B.Fab")
		)
		(fp_line
			(start 0.3048 -0.1016)
			(end 0.3048 0.9906)
			(stroke
				(width 0.1)
				(type default)
			)
			(layer "B.Fab")
		)
		(pad "1" smd rect
			(at 0 0 90)
			(size 0.508 0.508)
			(layers "B.Cu" "B.Mask" "B.Paste")
			(net "VCC_D_3V3")
		)
		(pad "2" smd rect
			(at 0 0.889 90)
			(size 0.508 0.508)
			(layers "B.Cu" "B.Mask" "B.Paste")
			(net "GND")
		)
		(zone
			(layer "B.Cu")
			(hatch none 0.5)
			(connect_pads
				(clearance 0)
			)
			(min_thickness 0.25)
			(keepout
				(tracks not_allowed)
				(vias allowed)
				(pads allowed)
				(copperpour not_allowed)
				(footprints allowed)
			)
			(placement
				(enabled no)
				(sheetname "")
			)
			(fill
				(thermal_gap 0.5)
				(thermal_bridge_width 0.5)
				(island_removal_mode 0)
			)
			(polygon
				(pts
					(xy 410.868368 -39.38397) (xy 410.868368 -39.89197) (xy 411.249368 -39.89197) (xy 411.249368 -39.38397)
				)
			)
		)
		(zone
			(layer "B.Cu")
			(hatch none 0.5)
			(connect_pads
				(clearance 0)
			)
			(min_thickness 0.25)
			(keepout
				(tracks allowed)
				(vias not_allowed)
				(pads allowed)
				(copperpour not_allowed)
				(footprints allowed)
			)
			(placement
				(enabled no)
				(sheetname "")
			)
			(fill
				(thermal_gap 0.5)
				(thermal_bridge_width 0.5)
				(island_removal_mode 0)
			)
			(polygon
				(pts
					(xy 411.249368 -39.38397) (xy 411.249368 -39.89197) (xy 410.868368 -39.89197) (xy 410.868368 -39.38397)
				)
			)
		)
	)
)
